# T6G (Grand Teton) — schematic netlist excerpt (pin names and nets, part order shuffled) for the footprints in the layout excerpt that follows; sources: Cadence DE-HDL packaged netlist, KiCad conversion of 04192023_DAF0TMB3IC0_F0TG_MB_C_brd_V02_OCP.brd

PC2239  Q_CAP  2.2UF 16V 20% X7R  pkg C0603  page 152 : A = P12V_SCM_AVIN_PD ; B = GND
R1014  Q_RES  1K 1% EMPTY  pkg 0201LF  page 287 : A = RT_CPU0_P1_ADDR3 ; B = GND
C6006  Q_CAP  0.1UF 25V 10% X7R  pkg 0402  page 113 : A = P2E_MB_BMC_TX_BUF2_DN<0> ; B = P2E_MB_BMC_TX_BUF_C_DN<0>

(kicad_pcb
	(version 20260206)
	(generator "pcbnew")
	(generator_version "10.0")
	(general
		(thickness 1.6)
		(legacy_teardrops no)
	)
	(paper "A4")
	(title_block
		(title "04192023_DAF0TMB3IC0_F0TG_MB_C_brd_V02_OCP.brd")
		(comment 1 "Grand Teton / footprints 2261-2263 of 8354")
	)
	(layers
		(0 "F.Cu" signal "TOP")
		(4 "In1.Cu" signal "GND")
		(6 "In2.Cu" signal "IN1")
		(8 "In3.Cu" signal "GND1")
		(10 "In4.Cu" signal "IN2")
		(12 "In5.Cu" signal "GND2")
		(14 "In6.Cu" signal "IN3")
		(16 "In7.Cu" signal "GND3")
		(18 "In8.Cu" signal "VCC")
		(20 "In9.Cu" signal "VCC1")
		(22 "In10.Cu" signal "GND4")
		(24 "In11.Cu" signal "IN4")
		(26 "In12.Cu" signal "GND5")
		(28 "In13.Cu" signal "IN5")
		(30 "In14.Cu" signal "GND6")
		(32 "In15.Cu" signal "IN6")
		(34 "In16.Cu" signal "GND7")
		(2 "B.Cu" signal "BOTTOM")
		(9 "F.Adhes" user "F.Adhesive")
		(11 "B.Adhes" user "B.Adhesive")
		(13 "F.Paste" user "Package Geometry/Pastemask Top")
		(15 "B.Paste" user "Package Geometry/Pastemask Bottom")
		(5 "F.SilkS" user "Ref Des/Silkscreen Top")
		(7 "B.SilkS" user "Ref Des/Silkscreen Bottom")
		(1 "F.Mask" user "Board Geometry/Soldermask Top")
		(3 "B.Mask" user "Board Geometry/Soldermask Bottom")
		(17 "Dwgs.User" user "User.Drawings")
		(19 "Cmts.User" user "User.Comments")
		(21 "Eco1.User" user "User.Eco1")
		(23 "Eco2.User" user "User.Eco2")
		(25 "Edge.Cuts" user "Board Geometry/Outline")
		(27 "Margin" user)
		(31 "F.CrtYd" user "Package Geometry/Place Bound Top")
		(29 "B.CrtYd" user "Package Geometry/Place Bound Bottom")
		(35 "F.Fab" user "Ref Des/Assembly Top")
		(33 "B.Fab" user "Ref Des/Assembly Bottom")
	)
	(footprint ""
		(layer "F.Cu")
		(at 174.635922 -25.846532 180)
		(property "Reference" "PC2239"
			(at 0 0 180)
			(layer "F.SilkS")
			(hide yes)
			(effects
				(font
					(size 1.27 1.27)
				)
			)
		)
		(property "Value" ""
			(at 0 0 180)
			(layer "F.Fab")
			(effects
				(font
					(size 1.27 1.27)
				)
			)
		)
		(duplicate_pad_numbers_are_jumpers no)
		(fp_line
			(start 1.2954 0.5842)
			(end -1.2954 0.5842)
			(stroke
				(width 0.1524)
				(type default)
			)
			(layer "F.SilkS")
		)
		(fp_line
			(start 1.2954 -0.5842)
			(end 1.2954 0.5842)
			(stroke
				(width 0.1524)
				(type default)
			)
			(layer "F.SilkS")
		)
		(fp_line
			(start -1.2954 0.5842)
			(end -1.2954 -0.5842)
			(stroke
				(width 0.1524)
				(type default)
			)
			(layer "F.SilkS")
		)
		(fp_line
			(start -1.2954 -0.5842)
			(end 1.2954 -0.5842)
			(stroke
				(width 0.1524)
				(type default)
			)
			(layer "F.SilkS")
		)
		(fp_line
			(start 1.1938 0.4064)
			(end 0.8636 0.4064)
			(stroke
				(width 0.1)
				(type default)
			)
			(layer "F.Fab")
		)
		(fp_line
			(start 1.1938 -0.4064)
			(end 1.1938 0.4064)
			(stroke
				(width 0.1)
				(type default)
			)
			(layer "F.Fab")
		)
		(fp_line
			(start 0.8636 0.4572)
			(end -0.8636 0.4572)
			(stroke
				(width 0.1)
				(type default)
			)
			(layer "F.Fab")
		)
		(fp_line
			(start 0.8636 0.4064)
			(end 0.8636 0.4572)
			(stroke
				(width 0.1)
				(type default)
			)
			(layer "F.Fab")
		)
		(fp_line
			(start 0.8636 -0.4064)
			(end 1.1938 -0.4064)
			(stroke
				(width 0.1)
				(type default)
			)
			(layer "F.Fab")
		)
		(fp_line
			(start 0.8636 -0.4572)
			(end 0.8636 -0.4064)
			(stroke
				(width 0.1)
				(type default)
			)
			(layer "F.Fab")
		)
		(fp_line
			(start -0.8636 0.4572)
			(end -0.8636 0.4064)
			(stroke
				(width 0.1)
				(type default)
			)
			(layer "F.Fab")
		)
		(fp_line
			(start -0.8636 0.4064)
			(end -1.1938 0.4064)
			(stroke
				(width 0.1)
				(type default)
			)
			(layer "F.Fab")
		)
		(fp_line
			(start -0.8636 -0.4064)
			(end -0.8636 -0.4572)
			(stroke
				(width 0.1)
				(type default)
			)
			(layer "F.Fab")
		)
		(fp_line
			(start -0.8636 -0.4572)
			(end 0.8636 -0.4572)
			(stroke
				(width 0.1)
				(type default)
			)
			(layer "F.Fab")
		)
		(fp_line
			(start -1.1938 0.4064)
			(end -1.1938 -0.4064)
			(stroke
				(width 0.1)
				(type default)
			)
			(layer "F.Fab")
		)
		(fp_line
			(start -1.1938 -0.4064)
			(end -0.8636 -0.4064)
			(stroke
				(width 0.1)
				(type default)
			)
			(layer "F.Fab")
		)
		(pad "1" smd rect
			(at -0.7366 0 90)
			(size 0.7112 0.8128)
			(layers "F.Cu" "F.Mask" "F.Paste")
			(net "P12V_SCM_AVIN_PD")
		)
		(pad "2" smd rect
			(at 0.7366 0 90)
			(size 0.7112 0.8128)
			(layers "F.Cu" "F.Mask" "F.Paste")
			(net "GND")
		)
	)
	(footprint ""
		(layer "F.Cu")
		(at 360.40949 -395.1732 90)
		(property "Reference" "R1014"
			(at 0 0 90)
			(layer "F.SilkS")
			(hide yes)
			(effects
				(font
					(size 1.27 1.27)
				)
			)
		)
		(property "Value" ""
			(at 0 0 90)
			(layer "F.Fab")
			(effects
				(font
					(size 1.27 1.27)
				)
			)
		)
		(duplicate_pad_numbers_are_jumpers no)
		(fp_line
			(start 0.32512 -0.175006)
			(end 0.32512 0.175006)
			(stroke
				(width 0.1)
				(type default)
			)
			(layer "F.Fab")
		)
		(fp_line
			(start -0.32512 -0.175006)
			(end 0.32512 -0.175006)
			(stroke
				(width 0.1)
				(type default)
			)
			(layer "F.Fab")
		)
		(fp_line
			(start 0.32512 0.175006)
			(end -0.32512 0.175006)
			(stroke
				(width 0.1)
				(type default)
			)
			(layer "F.Fab")
		)
		(fp_line
			(start -0.32512 0.175006)
			(end -0.32512 -0.175006)
			(stroke
				(width 0.1)
				(type default)
			)
			(layer "F.Fab")
		)
		(pad "1" smd rect
			(at -0.2667 0 90)
			(size 0.3048 0.381)
			(layers "F.Cu" "F.Mask" "F.Paste")
			(net "RT_CPU0_P1_ADDR3")
		)
		(pad "2" smd rect
			(at 0.2667 0 270)
			(size 0.3048 0.381)
			(layers "F.Cu" "F.Mask" "F.Paste")
			(net "GND")
		)
	)
	(footprint ""
		(layer "F.Cu")
		(at 27.73553 -422.330626)
		(property "Reference" "C6006"
			(at 0 0 0)
			(layer "F.SilkS")
			(hide yes)
			(effects
				(font
					(size 1.27 1.27)
				)
			)
		)
		(property "Value" ""
			(at 0 0 0)
			(layer "F.Fab")
			(effects
				(font
					(size 1.27 1.27)
				)
			)
		)
		(duplicate_pad_numbers_are_jumpers no)
		(fp_line
			(start -0.7874 -0.4064)
			(end 0.7874 -0.4064)
			(stroke
				(width 0.1524)
				(type default)
			)
			(layer "F.SilkS")
		)
		(fp_line
			(start -0.35433 0.4064)
			(end -0.7874 0.4064)
			(stroke
				(width 0.1524)
				(type default)
			)
			(layer "F.SilkS")
		)
		(fp_line
			(start 0.7874 -0.4064)
			(end 0.7874 0.284226)
			(stroke
				(width 0.1524)
				(type default)
			)
			(layer "F.SilkS")
		)
		(fp_line
			(start -0.6858 -0.3048)
			(end -0.1016 -0.3048)
			(stroke
				(width 0.1)
				(type default)
			)
			(layer "F.Fab")
		)
		(fp_line
			(start -0.6858 0.3048)
			(end -0.6858 -0.3048)
			(stroke
				(width 0.1)
				(type default)
			)
			(layer "F.Fab")
		)
		(fp_line
			(start -0.1016 -0.3048)
			(end -0.1016 -0.2794)
			(stroke
				(width 0.1)
				(type default)
			)
			(layer "F.Fab")
		)
		(fp_line
			(start -0.1016 -0.2794)
			(end 0.1016 -0.2794)
			(stroke
				(width 0.1)
				(type default)
			)
			(layer "F.Fab")
		)
		(fp_line
			(start -0.1016 0.2794)
			(end -0.1016 0.3048)
			(stroke
				(width 0.1)
				(type default)
			)
			(layer "F.Fab")
		)
		(fp_line
			(start -0.1016 0.3048)
			(end -0.6858 0.3048)
			(stroke
				(width 0.1)
				(type default)
			)
			(layer "F.Fab")
		)
		(fp_line
			(start 0.1016 -0.3048)
			(end 0.6858 -0.3048)
			(stroke
				(width 0.1)
				(type default)
			)
			(layer "F.Fab")
		)
		(fp_line
			(start 0.1016 -0.2794)
			(end 0.1016 -0.3048)
			(stroke
				(width 0.1)
				(type default)
			)
			(layer "F.Fab")
		)
		(fp_line
			(start 0.1016 0.2794)
			(end -0.1016 0.2794)
			(stroke
				(width 0.1)
				(type default)
			)
			(layer "F.Fab")
		)
		(fp_line
			(start 0.1016 0.3048)
			(end 0.1016 0.2794)
			(stroke
				(width 0.1)
				(type default)
			)
			(layer "F.Fab")
		)
		(fp_line
			(start 0.6858 -0.3048)
			(end 0.6858 0.3048)
			(stroke
				(width 0.1)
				(type default)
			)
			(layer "F.Fab")
		)
		(fp_line
			(start 0.6858 0.3048)
			(end 0.1016 0.3048)
			(stroke
				(width 0.1)
				(type default)
			)
			(layer "F.Fab")
		)
		(pad "1" smd rect
			(at -0.40005 0 180)
			(size 0.4572 0.508)
			(layers "F.Cu" "F.Mask" "F.Paste")
			(net "P2E_MB_BMC_TX_BUF2_DN<0>")
		)
		(pad "2" smd rect
			(at 0.40005 0 180)
			(size 0.4572 0.508)
			(layers "F.Cu" "F.Mask" "F.Paste")
			(net "P2E_MB_BMC_TX_BUF_C_DN<0>")
		)
	)
)
